G04 ================== begin FILE IDENTIFICATION RECORD ==================*
G04 Layout Name:  14545-sa.brd*
G04 Film Name:    DIF_REF_L3*
G04 File Format:  Gerber RS274X*
G04 File Origin:  Cadence Allegro 16.5-S056*
G04 Origin Date:  Fri Aug 01 17:59:04 2014*
G04 *
G04 Layer:  BOARD GEOMETRY/OUTLINE*
G04 Layer:  BOARD GEOMETRY/DIF_REF_L3*
G04 Layer:  BOARD GEOMETRY/PANEL_OUTLINE*
G04 *
G04 Offset:    (0.00 0.00)*
G04 Mirror:    No*
G04 Mode:      Positive*
G04 Rotation:  0*
G04 FullContactRelief:  No*
G04 UndefLineWidth:     6.00*
G04 ================== end FILE IDENTIFICATION RECORD ====================*
%FSLAX35Y35*MOIN*%
%IR0*IPPOS*OFA0.00000B0.00000*MIA0B0*SFA1.00000B1.00000*%
%ADD10C,.006*%
%ADD11C,.0045*%
G75*
%LPD*%
G75*
G54D10*
G01X-78741Y15000D02*
G03X-63741Y0I15000J0D01*
G01X-78741Y15000D02*
Y120047D01*
G01X-63741Y135047D02*
G03X-78741Y120047I0J-15000D01*
G01Y298866D02*
G03X-63741Y283866I15000J0D01*
G01X-78741Y319646D02*
Y298866D01*
G01X-63741Y334646D02*
G03X-78741Y319646I0J-15000D01*
G01Y908315D02*
G03X-63741Y893315I15000J0D01*
G01X-78741Y908315D02*
Y1104299D01*
G01X-63741Y1119299D02*
G03X-78741Y1104299I0J-15000D01*
G01Y1283118D02*
G03X-63741Y1268118I15000J0D01*
G01X-78741Y1304285D02*
Y1283118D01*
G01X-63741Y1319285D02*
G03X-78741Y1304285I0J-15000D01*
G01Y1892953D02*
G03X-63741Y1877953I15000J0D01*
G01X-78741Y1892953D02*
Y1977126D01*
G01X-63741Y1992126D02*
G03X-78741Y1977126I0J-15000D01*
G01X19882Y1197835D02*
X1969D01*
X0Y1195866D01*
Y832480D01*
X1969Y830512D01*
X19882D01*
G02Y823031I0J-3740D01*
G01X1969D01*
X0Y821063D01*
Y423031D01*
X1969Y421063D01*
X19882D01*
G02Y413583I0J-3740D01*
G01X1969D01*
X0Y411614D01*
Y223031D01*
X1969Y221063D01*
X19882D01*
G02Y213583I0J-3740D01*
G01X1969D01*
X0Y211614D01*
Y3937D01*
G03X3937Y0I3937J0D01*
G01X1029528D01*
G03X1033465Y3937I0J3937D01*
G01Y1424882D01*
X1029528Y1428819D01*
X1024213D01*
G02X1019291Y1433740I-1J4921D01*
G01Y1607933D01*
X1015354Y1611870D01*
X989744D01*
G02Y1616083I0J2107D01*
G01X1015354D01*
X1019291Y1620020D01*
Y1676496D01*
G02X1024213Y1681417I4921J0D01*
G01X1029528D01*
X1033465Y1685354D01*
Y1988189D01*
G03X1029528Y1992126I-3937J0D01*
G01X3937D01*
G03X0Y1988189I0J-3937D01*
G01Y1816732D01*
X1969Y1814764D01*
X19882D01*
G02Y1807283I0J-3740D01*
G01X1969D01*
X0Y1805315D01*
Y1407283D01*
X1969Y1405315D01*
X19882D01*
G02Y1397835I0J-3740D01*
G01X1969D01*
X0Y1395866D01*
Y1207283D01*
X1969Y1205315D01*
X19882D01*
G02Y1197835I0J-3740D01*
G01Y1197834D02*
X1969D01*
X0Y1195865D01*
Y832479D01*
X1969Y830511D01*
X19882D01*
G02Y823030I0J-3741D01*
G01X1969D01*
X0Y821062D01*
Y423030D01*
X1969Y421062D01*
X19882D01*
G02Y413582I0J-3740D01*
G01X1969D01*
X0Y411613D01*
Y223030D01*
X1969Y221062D01*
X19882D01*
G02Y213582I0J-3740D01*
G01X1969D01*
X0Y211613D01*
Y3936D01*
G03X3937Y-1I3937J0D01*
G01X1029528D01*
G03X1033465Y3936I0J3937D01*
G01Y1424881D01*
X1029528Y1428818D01*
X1024213D01*
G02X1019291Y1433739I-1J4921D01*
G01Y1607932D01*
X1015354Y1611869D01*
X989744D01*
G02Y1616082I0J2107D01*
G01X1015354D01*
X1019291Y1620019D01*
Y1676495D01*
G02X1024213Y1681416I4921J0D01*
G01X1029528D01*
X1033465Y1685353D01*
Y1988188D01*
G03X1029528Y1992125I-3937J0D01*
G01X3937D01*
G03X0Y1988188I0J-3937D01*
G01Y1816731D01*
X1969Y1814763D01*
X19882D01*
G02Y1807282I0J-3741D01*
G01X1969D01*
X0Y1805314D01*
Y1407282D01*
X1969Y1405314D01*
X19882D01*
G02Y1397834I0J-3740D01*
G01X1969D01*
X0Y1395865D01*
Y1207282D01*
X1969Y1205314D01*
X19882D01*
G02Y1197834I0J-3740D01*
G01X-7875Y0D02*
X-63741D01*
G01X-7875Y41772D02*
Y104969D01*
G01Y17252D02*
Y0D01*
G01Y41772D02*
G03X-1I3937J-1D01*
G01Y17213D02*
G03X-7875I-3937J0D01*
G01Y41772D02*
G03X-1I3937J-1D01*
G01Y17213D02*
G03X-7875I-3937J0D01*
G01Y129516D02*
Y135047D01*
G01D02*
X-63741D01*
G01X-7875Y129516D02*
G03X-1I3937J0D01*
G01Y104958D02*
G03X-7875I-3937J0D01*
G01Y283866D02*
Y300383D01*
G01X-19814Y283866D02*
X-63741D01*
G01X-7875D02*
X-19814D01*
G01X-1Y300383D02*
G03X-7875I-3937J0D01*
G01Y331986D02*
Y324003D01*
G01Y331986D02*
Y334646D01*
G01D02*
X-63741D01*
G01X-7875Y324003D02*
G03X-1I3937J0D01*
G01X-7875Y905988D02*
Y893315D01*
G01D02*
X-63741D01*
G01X-7875Y1069005D02*
Y933234D01*
G01D02*
G03X-1I3937J0D01*
G01Y905988D02*
G03X-7875I-3937J0D01*
G01Y1108863D02*
Y1119299D01*
G01X-19126D02*
X-7875D01*
G01X-15749D02*
X-63741D01*
G01X-7875Y1106300D02*
Y1111425D01*
G01Y1106300D02*
Y1092625D01*
G01D02*
G03X-1I3937J0D01*
G01Y1069005D02*
G03X-7875I-3937J0D01*
G01X-17894Y1268118D02*
X-7875D01*
G01Y1278280D02*
Y1268118D01*
G01Y1280567D02*
Y1275992D01*
G01X-15749Y1268118D02*
X-63741D01*
G01X-7875Y1309889D02*
G03X-1I3937J0D01*
G01Y1280567D02*
G03X-7875I-3937J0D01*
G01Y1309889D02*
G03X-1I3937J0D01*
G01Y1280567D02*
G03X-7875I-3937J0D01*
G01Y1309889D02*
Y1319285D01*
G01D02*
X-63741D01*
G01X-7875Y1889223D02*
Y1877953D01*
G01D02*
X-63741D01*
G01X-7875Y1912843D02*
Y1962926D01*
G01Y1912843D02*
G03X-1I3937J0D01*
G01Y1889223D02*
G03X-7875I-3937J0D01*
G01Y1912843D02*
G03X-1I3937J0D01*
G01Y1889223D02*
G03X-7875I-3937J0D01*
G01X-1Y1962926D02*
G03X-7875I-3937J0D01*
G01X-1D02*
G03X-7875I-3937J0D01*
G01Y1986546D02*
Y1992126D01*
G01D02*
X-63741D01*
G01X-7875Y1986546D02*
G03X-1I3937J0D01*
G01X-7875D02*
G03X-1I3937J0D01*
G01X37330Y-70164D02*
Y-82164D01*
G01X35030Y-70164D02*
X39630D01*
G01X41630Y-82164D02*
Y-70164D01*
G01Y-75964D02*
X42130Y-74964D01*
X42630Y-74364D01*
X43430Y-74164D01*
X44030Y-74364D01*
X44730Y-75164D01*
X45030Y-76364D01*
Y-82164D01*
G01X49330Y-74164D02*
Y-82164D01*
G01Y-70964D02*
X49130Y-70764D01*
Y-70364D01*
X49330Y-70164D01*
X49530Y-70364D01*
Y-70764D01*
X49330Y-70964D01*
G01X53830Y-80764D02*
X54330Y-81564D01*
X55030Y-82164D01*
X55630D01*
X56230Y-81764D01*
X56630Y-81164D01*
X56830Y-80364D01*
X56730Y-79164D01*
X56330Y-78564D01*
X54530Y-77364D01*
X54130Y-75964D01*
X54330Y-74964D01*
X54730Y-74364D01*
X55330Y-74164D01*
X55930Y-74364D01*
X56530Y-74964D01*
G01X65930Y-85164D02*
X66630Y-85964D01*
X67430Y-86164D01*
X68130Y-85964D01*
X68730Y-84964D01*
X69130Y-83564D01*
Y-74164D01*
G01Y-75764D02*
X68730Y-74964D01*
X68130Y-74364D01*
X67430Y-74164D01*
X66630Y-74564D01*
X66130Y-75364D01*
X65730Y-76764D01*
X65530Y-78164D01*
X65630Y-79364D01*
X66030Y-80764D01*
X66630Y-81764D01*
X67430Y-82164D01*
X68030Y-81964D01*
X68730Y-81164D01*
X69130Y-80364D01*
G01X71830Y-76764D02*
X75030D01*
X74730Y-75364D01*
X74230Y-74564D01*
X73530Y-74164D01*
X72830Y-74364D01*
X72230Y-74964D01*
X71830Y-76364D01*
X71630Y-77564D01*
Y-78764D01*
X71830Y-79964D01*
X72330Y-81164D01*
X72930Y-81964D01*
X73630Y-82164D01*
X74330Y-81764D01*
X75030Y-80564D01*
G01X77930Y-82164D02*
Y-74164D01*
G01Y-75764D02*
X78430Y-74964D01*
X78930Y-74364D01*
X79630Y-74164D01*
X80130Y-74364D01*
X80730Y-74964D01*
G01X83530Y-82164D02*
Y-70164D01*
G01Y-76164D02*
X84030Y-74964D01*
X84630Y-74364D01*
X85230Y-74164D01*
X86130Y-74564D01*
X86730Y-75364D01*
X87130Y-76764D01*
Y-78364D01*
X86930Y-79964D01*
X86530Y-81164D01*
X85830Y-81964D01*
X85230Y-82164D01*
X84630Y-81964D01*
X84030Y-81364D01*
X83530Y-80364D01*
G01X89830Y-76764D02*
X93030D01*
X92730Y-75364D01*
X92230Y-74564D01*
X91530Y-74164D01*
X90830Y-74364D01*
X90230Y-74964D01*
X89830Y-76364D01*
X89630Y-77564D01*
Y-78764D01*
X89830Y-79964D01*
X90330Y-81164D01*
X90930Y-81964D01*
X91630Y-82164D01*
X92330Y-81764D01*
X93030Y-80564D01*
G01X95930Y-82164D02*
Y-74164D01*
G01Y-75764D02*
X96430Y-74964D01*
X96930Y-74364D01*
X97630Y-74164D01*
X98130Y-74364D01*
X98730Y-74964D01*
G01X109330Y-74164D02*
Y-82164D01*
G01Y-70964D02*
X109130Y-70764D01*
Y-70364D01*
X109330Y-70164D01*
X109530Y-70364D01*
Y-70764D01*
X109330Y-70964D01*
G01X113830Y-80764D02*
X114330Y-81564D01*
X115030Y-82164D01*
X115630D01*
X116230Y-81764D01*
X116630Y-81164D01*
X116830Y-80364D01*
X116730Y-79164D01*
X116330Y-78564D01*
X114530Y-77364D01*
X114130Y-75964D01*
X114330Y-74964D01*
X114730Y-74364D01*
X115330Y-74164D01*
X115930Y-74364D01*
X116530Y-74964D01*
G01X125730Y-85164D02*
X126430Y-85964D01*
X127030Y-86164D01*
X127830Y-85764D01*
X128430Y-84764D01*
X128730Y-82964D01*
Y-74164D01*
G01Y-70964D02*
X128530Y-70764D01*
Y-70364D01*
X128730Y-70164D01*
X128930Y-70364D01*
Y-70764D01*
X128730Y-70964D01*
G01X131630Y-74164D02*
Y-79764D01*
X132030Y-81164D01*
X132630Y-81964D01*
X133330Y-82164D01*
X134030Y-81964D01*
X134630Y-81164D01*
X135030Y-79764D01*
G01Y-82164D02*
Y-74164D01*
G01X137830Y-80764D02*
X138330Y-81564D01*
X139030Y-82164D01*
X139630D01*
X140230Y-81764D01*
X140630Y-81164D01*
X140830Y-80364D01*
X140730Y-79164D01*
X140330Y-78564D01*
X138530Y-77364D01*
X138130Y-75964D01*
X138330Y-74964D01*
X138730Y-74364D01*
X139330Y-74164D01*
X139930Y-74364D01*
X140530Y-74964D01*
G01X145330Y-70164D02*
Y-82164D01*
G01X143930Y-74164D02*
X146730D01*
G01X156730Y-82164D02*
Y-71964D01*
X156930Y-70964D01*
X157330Y-70364D01*
X157930Y-70164D01*
X158530Y-70564D01*
X158830Y-71564D01*
G01X157630Y-74964D02*
X155630D01*
G01X163330Y-82164D02*
X162730Y-81964D01*
X162130Y-81164D01*
X161730Y-79764D01*
X161530Y-78164D01*
X161730Y-76564D01*
X162130Y-75164D01*
X162730Y-74364D01*
X163330Y-74164D01*
X163930Y-74364D01*
X164530Y-75164D01*
X164930Y-76564D01*
X165030Y-78164D01*
X164930Y-79764D01*
X164530Y-81164D01*
X163930Y-81964D01*
X163330Y-82164D01*
G01X167930D02*
Y-74164D01*
G01Y-75764D02*
X168430Y-74964D01*
X168930Y-74364D01*
X169630Y-74164D01*
X170130Y-74364D01*
X170730Y-74964D01*
G01X179230Y-85764D02*
X179830Y-86164D01*
X180630Y-85764D01*
X181130Y-84964D01*
X181530Y-83964D01*
X182130Y-80764D01*
X183430Y-74164D01*
G01X180230D02*
X182130Y-80764D01*
G01X187330Y-82164D02*
X186730Y-81964D01*
X186130Y-81164D01*
X185730Y-79764D01*
X185530Y-78164D01*
X185730Y-76564D01*
X186130Y-75164D01*
X186730Y-74364D01*
X187330Y-74164D01*
X187930Y-74364D01*
X188530Y-75164D01*
X188930Y-76564D01*
X189030Y-78164D01*
X188930Y-79764D01*
X188530Y-81164D01*
X187930Y-81964D01*
X187330Y-82164D01*
G01X191630Y-74164D02*
Y-79764D01*
X192030Y-81164D01*
X192630Y-81964D01*
X193330Y-82164D01*
X194030Y-81964D01*
X194630Y-81164D01*
X195030Y-79764D01*
G01Y-82164D02*
Y-74164D01*
G01X203930Y-82164D02*
Y-74164D01*
G01Y-75764D02*
X204430Y-74964D01*
X204930Y-74364D01*
X205630Y-74164D01*
X206130Y-74364D01*
X206730Y-74964D01*
G01X209830Y-76764D02*
X213030D01*
X212730Y-75364D01*
X212230Y-74564D01*
X211530Y-74164D01*
X210830Y-74364D01*
X210230Y-74964D01*
X209830Y-76364D01*
X209630Y-77564D01*
Y-78764D01*
X209830Y-79964D01*
X210330Y-81164D01*
X210930Y-81964D01*
X211630Y-82164D01*
X212330Y-81764D01*
X213030Y-80564D01*
G01X216730Y-82164D02*
Y-71964D01*
X216930Y-70964D01*
X217330Y-70364D01*
X217930Y-70164D01*
X218530Y-70564D01*
X218830Y-71564D01*
G01X217630Y-74964D02*
X215630D01*
G01X221830Y-76764D02*
X225030D01*
X224730Y-75364D01*
X224230Y-74564D01*
X223530Y-74164D01*
X222830Y-74364D01*
X222230Y-74964D01*
X221830Y-76364D01*
X221630Y-77564D01*
Y-78764D01*
X221830Y-79964D01*
X222330Y-81164D01*
X222930Y-81964D01*
X223630Y-82164D01*
X224330Y-81764D01*
X225030Y-80564D01*
G01X227930Y-82164D02*
Y-74164D01*
G01Y-75764D02*
X228430Y-74964D01*
X228930Y-74364D01*
X229630Y-74164D01*
X230130Y-74364D01*
X230730Y-74964D01*
G01X233830Y-76764D02*
X237030D01*
X236730Y-75364D01*
X236230Y-74564D01*
X235530Y-74164D01*
X234830Y-74364D01*
X234230Y-74964D01*
X233830Y-76364D01*
X233630Y-77564D01*
Y-78764D01*
X233830Y-79964D01*
X234330Y-81164D01*
X234930Y-81964D01*
X235630Y-82164D01*
X236330Y-81764D01*
X237030Y-80564D01*
G01X239630Y-82164D02*
Y-74164D01*
G01Y-76164D02*
X240030Y-75164D01*
X240630Y-74364D01*
X241430Y-74164D01*
X242130Y-74364D01*
X242730Y-75164D01*
X243030Y-76564D01*
Y-82164D01*
G01X248930Y-75164D02*
X248230Y-74364D01*
X247630Y-74164D01*
X246830Y-74564D01*
X246230Y-75364D01*
X245830Y-76764D01*
X245730Y-78164D01*
X245830Y-79564D01*
X246230Y-80764D01*
X246830Y-81764D01*
X247630Y-82164D01*
X248330Y-81764D01*
X248930Y-80964D01*
G01X251830Y-76764D02*
X255030D01*
X254730Y-75364D01*
X254230Y-74564D01*
X253530Y-74164D01*
X252830Y-74364D01*
X252230Y-74964D01*
X251830Y-76364D01*
X251630Y-77564D01*
Y-78764D01*
X251830Y-79964D01*
X252330Y-81164D01*
X252930Y-81964D01*
X253630Y-82164D01*
X254330Y-81764D01*
X255030Y-80564D01*
G01X265330Y-70164D02*
Y-82164D01*
G01X263930Y-74164D02*
X266730D01*
G01X271330Y-82164D02*
X270730Y-81964D01*
X270130Y-81164D01*
X269730Y-79764D01*
X269530Y-78164D01*
X269730Y-76564D01*
X270130Y-75164D01*
X270730Y-74364D01*
X271330Y-74164D01*
X271930Y-74364D01*
X272530Y-75164D01*
X272930Y-76564D01*
X273030Y-78164D01*
X272930Y-79764D01*
X272530Y-81164D01*
X271930Y-81964D01*
X271330Y-82164D01*
G01X282730D02*
Y-71964D01*
X282930Y-70964D01*
X283330Y-70364D01*
X283930Y-70164D01*
X284530Y-70564D01*
X284830Y-71564D01*
G01X283630Y-74964D02*
X281630D01*
G01X289330Y-74164D02*
Y-82164D01*
G01Y-70964D02*
X289130Y-70764D01*
Y-70364D01*
X289330Y-70164D01*
X289530Y-70364D01*
Y-70764D01*
X289330Y-70964D01*
G01X293630Y-82164D02*
Y-74164D01*
G01Y-76164D02*
X294030Y-75164D01*
X294630Y-74364D01*
X295430Y-74164D01*
X296130Y-74364D01*
X296730Y-75164D01*
X297030Y-76564D01*
Y-82164D01*
G01X303130Y-70164D02*
Y-82164D01*
G01Y-80364D02*
X302730Y-81364D01*
X302130Y-81964D01*
X301430Y-82164D01*
X300630Y-81764D01*
X300030Y-80764D01*
X299630Y-79564D01*
X299530Y-78164D01*
X299630Y-76764D01*
X300030Y-75564D01*
X300630Y-74564D01*
X301430Y-74164D01*
X302130Y-74364D01*
X302630Y-74764D01*
X303130Y-75564D01*
G01X313330Y-70164D02*
Y-82164D01*
G01X311930Y-74164D02*
X314730D01*
G01X317630Y-82164D02*
Y-70164D01*
G01Y-75964D02*
X318130Y-74964D01*
X318630Y-74364D01*
X319430Y-74164D01*
X320030Y-74364D01*
X320730Y-75164D01*
X321030Y-76364D01*
Y-82164D01*
G01X323830Y-76764D02*
X327030D01*
X326730Y-75364D01*
X326230Y-74564D01*
X325530Y-74164D01*
X324830Y-74364D01*
X324230Y-74964D01*
X323830Y-76364D01*
X323630Y-77564D01*
Y-78764D01*
X323830Y-79964D01*
X324330Y-81164D01*
X324930Y-81964D01*
X325630Y-82164D01*
X326330Y-81764D01*
X327030Y-80564D01*
G01X339130Y-70164D02*
Y-82164D01*
G01Y-80364D02*
X338730Y-81364D01*
X338130Y-81964D01*
X337430Y-82164D01*
X336630Y-81764D01*
X336030Y-80764D01*
X335630Y-79564D01*
X335530Y-78164D01*
X335630Y-76764D01*
X336030Y-75564D01*
X336630Y-74564D01*
X337430Y-74164D01*
X338130Y-74364D01*
X338630Y-74764D01*
X339130Y-75564D01*
G01X343330Y-74164D02*
Y-82164D01*
G01Y-70964D02*
X343130Y-70764D01*
Y-70364D01*
X343330Y-70164D01*
X343530Y-70364D01*
Y-70764D01*
X343330Y-70964D01*
G01X348730Y-82164D02*
Y-71964D01*
X348930Y-70964D01*
X349330Y-70364D01*
X349930Y-70164D01*
X350530Y-70564D01*
X350830Y-71564D01*
G01X349630Y-74964D02*
X347630D01*
G01X354730Y-82164D02*
Y-71964D01*
X354930Y-70964D01*
X355330Y-70364D01*
X355930Y-70164D01*
X356530Y-70564D01*
X356830Y-71564D01*
G01X355630Y-74964D02*
X353630D01*
G01X359830Y-76764D02*
X363030D01*
X362730Y-75364D01*
X362230Y-74564D01*
X361530Y-74164D01*
X360830Y-74364D01*
X360230Y-74964D01*
X359830Y-76364D01*
X359630Y-77564D01*
Y-78764D01*
X359830Y-79964D01*
X360330Y-81164D01*
X360930Y-81964D01*
X361630Y-82164D01*
X362330Y-81764D01*
X363030Y-80564D01*
G01X365930Y-82164D02*
Y-74164D01*
G01Y-75764D02*
X366430Y-74964D01*
X366930Y-74364D01*
X367630Y-74164D01*
X368130Y-74364D01*
X368730Y-74964D01*
G01X371830Y-76764D02*
X375030D01*
X374730Y-75364D01*
X374230Y-74564D01*
X373530Y-74164D01*
X372830Y-74364D01*
X372230Y-74964D01*
X371830Y-76364D01*
X371630Y-77564D01*
Y-78764D01*
X371830Y-79964D01*
X372330Y-81164D01*
X372930Y-81964D01*
X373630Y-82164D01*
X374330Y-81764D01*
X375030Y-80564D01*
G01X377630Y-82164D02*
Y-74164D01*
G01Y-76164D02*
X378030Y-75164D01*
X378630Y-74364D01*
X379430Y-74164D01*
X380130Y-74364D01*
X380730Y-75164D01*
X381030Y-76564D01*
Y-82164D01*
G01X385330Y-70164D02*
Y-82164D01*
G01X383930Y-74164D02*
X386730D01*
G01X391330D02*
Y-82164D01*
G01Y-70964D02*
X391130Y-70764D01*
Y-70364D01*
X391330Y-70164D01*
X391530Y-70364D01*
Y-70764D01*
X391330Y-70964D01*
G01X399130Y-82164D02*
Y-74164D01*
G01Y-75564D02*
X398730Y-74764D01*
X398130Y-74364D01*
X397430Y-74164D01*
X396730Y-74564D01*
X396130Y-75364D01*
X395730Y-76564D01*
X395530Y-78164D01*
X395730Y-79764D01*
X396130Y-80964D01*
X396730Y-81764D01*
X397430Y-82164D01*
X398130Y-81964D01*
X398730Y-81364D01*
X399130Y-80564D01*
G01X403330Y-82164D02*
Y-70164D01*
G01X415330D02*
Y-82164D01*
G01X413930Y-74164D02*
X416730D01*
G01X419930Y-82164D02*
Y-74164D01*
G01Y-75764D02*
X420430Y-74964D01*
X420930Y-74364D01*
X421630Y-74164D01*
X422130Y-74364D01*
X422730Y-74964D01*
G01X429130Y-82164D02*
Y-74164D01*
G01Y-75564D02*
X428730Y-74764D01*
X428130Y-74364D01*
X427430Y-74164D01*
X426730Y-74564D01*
X426130Y-75364D01*
X425730Y-76564D01*
X425530Y-78164D01*
X425730Y-79764D01*
X426130Y-80964D01*
X426730Y-81764D01*
X427430Y-82164D01*
X428130Y-81964D01*
X428730Y-81364D01*
X429130Y-80564D01*
G01X434930Y-75164D02*
X434230Y-74364D01*
X433630Y-74164D01*
X432830Y-74564D01*
X432230Y-75364D01*
X431830Y-76764D01*
X431730Y-78164D01*
X431830Y-79564D01*
X432230Y-80764D01*
X432830Y-81764D01*
X433630Y-82164D01*
X434330Y-81764D01*
X434930Y-80964D01*
G01X437830Y-76764D02*
X441030D01*
X440730Y-75364D01*
X440230Y-74564D01*
X439530Y-74164D01*
X438830Y-74364D01*
X438230Y-74964D01*
X437830Y-76364D01*
X437630Y-77564D01*
Y-78764D01*
X437830Y-79964D01*
X438330Y-81164D01*
X438930Y-81964D01*
X439630Y-82164D01*
X440330Y-81764D01*
X441030Y-80564D01*
G01X443830Y-80764D02*
X444330Y-81564D01*
X445030Y-82164D01*
X445630D01*
X446230Y-81764D01*
X446630Y-81164D01*
X446830Y-80364D01*
X446730Y-79164D01*
X446330Y-78564D01*
X444530Y-77364D01*
X444130Y-75964D01*
X444330Y-74964D01*
X444730Y-74364D01*
X445330Y-74164D01*
X445930Y-74364D01*
X446530Y-74964D01*
G01X457330Y-74164D02*
Y-82164D01*
G01Y-70964D02*
X457130Y-70764D01*
Y-70364D01*
X457330Y-70164D01*
X457530Y-70364D01*
Y-70764D01*
X457330Y-70964D01*
G01X461630Y-82164D02*
Y-74164D01*
G01Y-76164D02*
X462030Y-75164D01*
X462630Y-74364D01*
X463430Y-74164D01*
X464130Y-74364D01*
X464730Y-75164D01*
X465030Y-76564D01*
Y-82164D01*
G01X475330D02*
Y-70164D01*
G01X483130Y-82164D02*
Y-74164D01*
G01Y-75564D02*
X482730Y-74764D01*
X482130Y-74364D01*
X481430Y-74164D01*
X480730Y-74564D01*
X480130Y-75364D01*
X479730Y-76564D01*
X479530Y-78164D01*
X479730Y-79764D01*
X480130Y-80964D01*
X480730Y-81764D01*
X481430Y-82164D01*
X482130Y-81964D01*
X482730Y-81364D01*
X483130Y-80564D01*
G01X485230Y-85764D02*
X485830Y-86164D01*
X486630Y-85764D01*
X487130Y-84964D01*
X487530Y-83964D01*
X488130Y-80764D01*
X489430Y-74164D01*
G01X486230D02*
X488130Y-80764D01*
G01X491830Y-76764D02*
X495030D01*
X494730Y-75364D01*
X494230Y-74564D01*
X493530Y-74164D01*
X492830Y-74364D01*
X492230Y-74964D01*
X491830Y-76364D01*
X491630Y-77564D01*
Y-78764D01*
X491830Y-79964D01*
X492330Y-81164D01*
X492930Y-81964D01*
X493630Y-82164D01*
X494330Y-81764D01*
X495030Y-80564D01*
G01X497930Y-82164D02*
Y-74164D01*
G01Y-75764D02*
X498430Y-74964D01*
X498930Y-74364D01*
X499630Y-74164D01*
X500130Y-74364D01*
X500730Y-74964D01*
G01X509330Y-70164D02*
Y-82164D01*
X513330D01*
G01X515130Y-79764D02*
X515730Y-81164D01*
X516530Y-81964D01*
X517430Y-82164D01*
X518230Y-81964D01*
X519030Y-80964D01*
X519530Y-79764D01*
X519630Y-78564D01*
X519430Y-77164D01*
X518730Y-76164D01*
X518030Y-75764D01*
X517130D01*
G01X518030D02*
X518630Y-75164D01*
X519130Y-74164D01*
X519330Y-72964D01*
X519130Y-71764D01*
X518630Y-70764D01*
X517730Y-70164D01*
X516830Y-70364D01*
X515930Y-71164D01*
G01X1041337Y24677D02*
Y0D01*
G01Y217343D02*
Y48297D01*
G01Y0D02*
X1097204D01*
G01X1033463Y48297D02*
G03X1041337I3937J0D01*
G01Y24677D02*
G03X1033463I-3937J0D01*
G01Y48297D02*
G03X1041337I3937J0D01*
G01Y24677D02*
G03X1033463I-3937J0D01*
G01X1041337Y217343D02*
G03X1033463I-3937J0D01*
G01X1041337D02*
G03X1033463I-3937J0D01*
G01X1041337Y445039D02*
Y240963D01*
G01X1033463D02*
G03X1041337I3937J0D01*
G01X1033463D02*
G03X1041337I3937J0D01*
G01Y697474D02*
Y468601D01*
G01X1033463Y468659D02*
G03X1041337I3937J0D01*
G01Y445039D02*
G03X1033463I-3937J0D01*
G01Y468659D02*
G03X1041337I3937J0D01*
G01Y445039D02*
G03X1033463I-3937J0D01*
G01X1041337Y996851D02*
Y721093D01*
G01X1033463D02*
G03X1041337I3937J0D01*
G01Y697474D02*
G03X1033463I-3937J-1D01*
G01Y721093D02*
G03X1041337I3937J0D01*
G01Y697474D02*
G03X1033463I-3937J-1D01*
G01X1041337Y1344059D02*
Y1020472D01*
G01X1033463D02*
G03X1041337I3937J0D01*
G01Y996851D02*
G03X1033463I-3937J1D01*
G01Y1020472D02*
G03X1041337I3937J0D01*
G01Y996851D02*
G03X1033463I-3937J1D01*
G01X1041337Y1367679D02*
Y1393701D01*
G01X1033463Y1367679D02*
G03X1041337I3937J0D01*
G01Y1344059D02*
G03X1033463I-3937J0D01*
G01Y1367679D02*
G03X1041337I3937J0D01*
G01Y1344059D02*
G03X1033463I-3937J0D01*
G01X1041337Y1393701D02*
X1097204D01*
G01X1041337Y1733129D02*
Y1716535D01*
G01X1065042D02*
X1041337D01*
G01X1056337D02*
X1097204D01*
G01X1041337Y1739719D02*
Y1731535D01*
G01Y1959242D02*
Y1763311D01*
G01X1033463Y1763339D02*
G03X1041337I3937J0D01*
G01Y1739719D02*
G03X1033463I-3937J0D01*
G01Y1763339D02*
G03X1041337I3937J0D01*
G01Y1739719D02*
G03X1033463I-3937J0D01*
G01X1041337Y1959242D02*
G03X1033463I-3937J0D01*
G01X1041337D02*
G03X1033463I-3937J0D01*
G01X1041337Y1992126D02*
X1097204D01*
G01X1041337Y1982862D02*
Y1992126D01*
G01X1033463Y1982862D02*
G03X1041337I3937J0D01*
G01X1033463D02*
G03X1041337I3937J0D01*
G01X1112204Y648419D02*
Y15000D01*
G01X1097204Y0D02*
G03X1112204Y15000I0J15000D01*
G01Y656293D02*
G03Y648419I0J-3937D01*
G01Y1378701D02*
Y656293D01*
G01Y1378701D02*
G03X1097204Y1393701I-15000J0D01*
G01Y1716535D02*
G03X1112204Y1731535I0J15000D01*
G01Y1977126D02*
Y1731535D01*
G01Y1977126D02*
G03X1097204Y1992126I-15000J0D01*
G54D11*
G01X31039Y480831D02*
G03X28927Y479956I0J-2987D01*
G01D02*
G02X28573Y479809I-354J353D01*
G01D02*
X27807D01*
G01D02*
G02X27181Y480068I0J886D01*
G01D02*
X27062Y480187D01*
G01D02*
G02X26921Y480528I342J341D01*
G01D02*
Y480632D01*
G01D02*
G03X26884Y480817I-483J0D01*
G01D02*
X26720Y481213D01*
G01X113708Y515218D02*
X79369Y480880D01*
G01D02*
G02X76352Y479631I-3016J3017D01*
G01D02*
X31040D01*
G01D02*
G03X29777Y479107I1J-1786D01*
G01D02*
G02X29561Y478924I-1203J1201D01*
G01D02*
G02X27936Y478404I-1625J2278D01*
G01D02*
X26299D01*
G01X145469Y543327D02*
X69095Y466953D01*
G01D02*
G02X64580Y465083I-4515J4515D01*
G01D02*
X30154D01*
G01D02*
G03X28884Y464557I0J-1796D01*
G01D02*
G02X26914I-985J985D01*
G01D02*
G02X26499Y465559I1002J1002D01*
G01D02*
Y466250D01*
G01X146318Y542478D02*
X69944Y466104D01*
G01D02*
G02X64582Y463883I-5362J5362D01*
G01D02*
X30153D01*
G01D02*
G03X29733Y463708I2J-596D01*
G01D02*
G02X27841Y462948I-1835J1833D01*
G01D02*
X27265Y462961D01*
G01D02*
G03X26486Y462648I-23J-1068D01*
G01X95117Y519550D02*
X73469D01*
G01D02*
G02X59348Y525399I0J19970D01*
G01D02*
X58208Y526540D01*
G01D02*
G03X54499Y528074I-3706J-3710D01*
G01D02*
Y528075D01*
G01D02*
X29561D01*
G01D02*
G02X26599Y529302I0J4189D01*
G01Y525648D02*
Y525867D01*
G01D02*
G02X28158Y527061I1237J0D01*
G01D02*
G03X29562Y526875I1404J5202D01*
G01D02*
X37519D01*
G01D02*
G02X38259Y526505I-7J-940D01*
G01D02*
G03X38999Y526135I747J570D01*
G01D02*
X40349D01*
G01D02*
G03X41089Y526505I-7J940D01*
G01D02*
G02X41829Y526875I747J-570D01*
G01D02*
X43179D01*
G01D02*
G02X43919Y526505I-7J-940D01*
G01D02*
G03X44659Y526135I747J570D01*
G01D02*
X46009D01*
G01D02*
G03X46749Y526505I-7J940D01*
G01D02*
G02X47489Y526875I747J-570D01*
G01D02*
X48839D01*
G01D02*
G02X49579Y526505I-7J-940D01*
G01D02*
G03X50319Y526135I747J570D01*
G01D02*
X51669D01*
G01D02*
G03X52409Y526505I-7J940D01*
G01D02*
G02X53149Y526875I747J-570D01*
G01D02*
X54499D01*
G01D02*
G02X57359Y525691I1J-4044D01*
G01D02*
X58499Y524550D01*
G01D02*
G03X73470Y518350I14969J14970D01*
G01D02*
X76557D01*
G01D02*
G02X77297Y517980I-8J-940D01*
G01D02*
G03X78037Y517610I747J570D01*
G01D02*
X79387D01*
G01D02*
G03X80127Y517980I-8J940D01*
G01D02*
G02X80867Y518350I747J-570D01*
G01D02*
X82217D01*
G01D02*
G02X82957Y517980I-8J-940D01*
G01D02*
G03X83697Y517610I747J570D01*
G01D02*
X85047D01*
G01D02*
G03X85787Y517980I-8J940D01*
G01D02*
G02X86527Y518350I747J-570D01*
G01D02*
X87877D01*
G01D02*
G02X88617Y517980I-7J-940D01*
G01D02*
G03X89357Y517610I747J570D01*
G01D02*
X90707D01*
G01D02*
G03X91447Y517980I-7J940D01*
G01D02*
G02X92187Y518350I747J-570D01*
G01D02*
X95117D01*
G01X114269Y517478D02*
X78520Y481729D01*
G01D02*
G02X76352Y480831I-2168J2168D01*
G01D02*
X31039D01*
G01X26720Y481213D02*
G03X26686Y481386I-452J1D01*
G01D02*
X26515Y481798D01*
G01X98900Y513400D02*
G02X98000Y515573I2173J2173D01*
G01D02*
Y516456D01*
G01D02*
G03X97049Y518749I-3245J-2D01*
G01D02*
Y518750D01*
G01D02*
G03X95117Y519550I-1932J-1933D01*
G01Y518350D02*
G02X96201Y517901I0J-1533D01*
G01D02*
G02X96800Y516455I-1446J-1446D01*
G01D02*
Y515900D01*
G01D02*
G02X95951Y513852I-2897J1D01*
G01D02*
X95500Y513400D01*
G01X115851Y807000D02*
Y520376D01*
G01D02*
G02X114920Y518128I-3179J0D01*
G01D02*
X114270Y517478D01*
G01D02*
X114269D01*
G01X117051Y807000D02*
Y520376D01*
G01D02*
G02X115769Y517279I-4379J-1D01*
G01D02*
X113708Y515218D01*
G01X146639Y563967D02*
Y562617D01*
G01D02*
G02X146269Y561877I-940J7D01*
G01D02*
G03X145899Y561137I570J-748D01*
G01D02*
Y559787D01*
G01D02*
G03X146269Y559047I940J7D01*
G01D02*
G02X146639Y558307I-570J-748D01*
G01D02*
Y556957D01*
G01D02*
G02X146269Y556217I-940J7D01*
G01D02*
G03X145899Y555477I570J-747D01*
G01D02*
Y554127D01*
G01D02*
G03X146269Y553387I940J7D01*
G01D02*
G02X146639Y552647I-570J-747D01*
G01D02*
Y546150D01*
G01D02*
G02X145469Y543327I-3993J1D01*
G01X147839Y597550D02*
Y546149D01*
G01D02*
G02X146318Y542478I-5193J1D01*
G01X131400Y644600D02*
G02X130200Y647497I2897J2897D01*
G01X148271Y648561D02*
Y642378D01*
G01D02*
G03X151199Y639450I2928J0D01*
G01D02*
X154385D01*
G01D02*
G02X156799Y638450I0J-3414D01*
G01D02*
G02X157799Y636036I-2414J-2414D01*
G01D02*
Y612172D01*
G01D02*
G02X156651Y609398I-3921J-2D01*
G01D02*
X156650Y609399D01*
G01D02*
X147938Y600686D01*
G01D02*
G03X146640Y597550I3136J-3135D01*
G01D02*
X146639D01*
G01D02*
Y589784D01*
G01D02*
G02X146269Y589044I-940J7D01*
G01D02*
G03X145899Y588304I570J-748D01*
G01D02*
Y586954D01*
G01D02*
G03X146269Y586214I940J7D01*
G01D02*
G02X146639Y585474I-570J-748D01*
G01D02*
Y584124D01*
G01D02*
G02X146269Y583384I-940J7D01*
G01D02*
G03X145899Y582644I570J-748D01*
G01D02*
Y581294D01*
G01D02*
G03X146269Y580554I940J7D01*
G01D02*
G02X146639Y579814I-570J-748D01*
G01D02*
Y573937D01*
G01D02*
G02X146269Y573197I-940J7D01*
G01D02*
G03X145899Y572457I570J-747D01*
G01D02*
Y571107D01*
G01D02*
G03X146269Y570367I940J7D01*
G01D02*
G02X146639Y569627I-570J-747D01*
G01D02*
Y568277D01*
G01D02*
G02X146269Y567537I-940J7D01*
G01D02*
G03X145899Y566797I570J-748D01*
G01D02*
Y565447D01*
G01D02*
G03X146269Y564707I940J7D01*
G01D02*
G02X146639Y563967I-570J-748D01*
G01X127999Y645550D02*
G03X129000Y647967I-2417J2417D01*
G01X149471Y648562D02*
Y642378D01*
G01D02*
G03X151199Y640650I1728J0D01*
G01D02*
X154386D01*
G01D02*
G02X157648Y639299I0J-4614D01*
G01D02*
G02X158999Y636037I-3263J-3262D01*
G01D02*
Y612171D01*
G01D02*
G02X157499Y608550I-5121J0D01*
G01D02*
X148787Y599837D01*
G01D02*
G03X147839Y597550I2287J-2288D01*
G01X130200Y647497D02*
Y648800D01*
G01D02*
G03X129210Y651190I-3380J0D01*
G01D02*
X127800Y652600D01*
G01D02*
G02X127100Y654290I1690J1690D01*
G01D02*
Y657700D01*
G01D02*
G02X127948Y659748I2897J0D01*
G01D02*
X128400Y660200D01*
G01D02*
G02X129849Y660800I1449J-1449D01*
G01D02*
X136627D01*
G01D02*
G02X138800Y659900I0J-3073D01*
G01D02*
X146950Y651750D01*
G01D02*
G02X148271Y648561I-3189J-3189D01*
G01X129000Y647967D02*
Y648799D01*
G01D02*
G03X128361Y650341I-2180J0D01*
G01D02*
X126951Y651751D01*
G01D02*
G02X125900Y654290I2539J2538D01*
G01D02*
Y657699D01*
G01D02*
G02X127099Y660597I4097J2D01*
G01D02*
X127551Y661049D01*
G01D02*
X127552Y661048D01*
G01D02*
G02X129850Y662000I2298J-2297D01*
G01D02*
X136626D01*
G01D02*
G02X139648Y660748I0J-4273D01*
G01D02*
X139649Y660749D01*
G01D02*
X147799Y652599D01*
G01D02*
X147798Y652598D01*
G01D02*
G02X149471Y648562I-4037J-4038D01*
G01X122099Y819233D02*
G02X118752Y811148I-11433J-2D01*
G01D02*
X118751Y811149D01*
G01D02*
X116733Y809131D01*
G01D02*
G03X115851Y807000I2131J-2130D01*
G01X123300Y819233D02*
G02X119600Y810300I-12633J0D01*
G01D02*
X117582Y808282D01*
G01D02*
G03X117051Y807000I1282J-1282D01*
G01X122100Y1036164D02*
Y819232D01*
G01D02*
X122099Y819233D01*
G01X123300Y1036163D02*
Y819233D01*
G01X123999Y1050650D02*
X124811Y1051463D01*
G01D02*
G02X125745Y1051850I934J-934D01*
G01D02*
X126999D01*
G01D02*
Y1051849D01*
G01D02*
G02X128194Y1051355I1J-1690D01*
G01D02*
G02X128799Y1049894I-1461J-1461D01*
G01D02*
Y1047140D01*
G01D02*
G02X128099Y1045450I-2390J0D01*
G01D02*
X124424Y1041775D01*
G01D02*
G03X122100Y1036164I5612J-5611D01*
G01X123999Y1054050D02*
G03X126001Y1053075I2414J2414D01*
G01D02*
X126002D01*
G01D02*
G03X126413Y1053050I412J3389D01*
G01D02*
X127000D01*
G01D02*
G02X129042Y1052204I-1J-2890D01*
G01D02*
Y1052203D01*
G01D02*
G02X129999Y1049893I-2309J-2310D01*
G01D02*
Y1047141D01*
G01D02*
G02X128947Y1044602I-3590J0D01*
G01D02*
X128948Y1044601D01*
G01D02*
X125273Y1040926D01*
G01D02*
G03X123300Y1036163I4763J-4763D01*
M02*
